# T6G (Grand Teton) — schematic netlist excerpt (pin names and nets, part order shuffled) for the footprints in the layout excerpt that follows; sources: Cadence DE-HDL packaged netlist, KiCad conversion of 04192023_DAF0TMB3IC0_F0TG_MB_C_brd_V02_OCP.brd

R1558  Q_RES  33 5% CHIP  pkg 0402LF  page 81 : A = RST_ESPI_CPU0_RSTOUT_R_N ; B = RST_ESPI_CPU0_RSTOUT_N
R1576  Q_RES  49.9 1% CHIP  pkg 0402LF  page 94 : A = I3C_SPD_DDRGL_CPU0_SCL ; B = I3C_SPD_DDRI_CPU0_SCL

(kicad_pcb
	(version 20260206)
	(generator "pcbnew")
	(generator_version "10.0")
	(general
		(thickness 1.6)
		(legacy_teardrops no)
	)
	(paper "A4")
	(title_block
		(title "04192023_DAF0TMB3IC0_F0TG_MB_C_brd_V02_OCP.brd")
		(comment 1 "Grand Teton / footprints 7765-7766 of 8354")
	)
	(layers
		(0 "F.Cu" signal "TOP")
		(4 "In1.Cu" signal "GND")
		(6 "In2.Cu" signal "IN1")
		(8 "In3.Cu" signal "GND1")
		(10 "In4.Cu" signal "IN2")
		(12 "In5.Cu" signal "GND2")
		(14 "In6.Cu" signal "IN3")
		(16 "In7.Cu" signal "GND3")
		(18 "In8.Cu" signal "VCC")
		(20 "In9.Cu" signal "VCC1")
		(22 "In10.Cu" signal "GND4")
		(24 "In11.Cu" signal "IN4")
		(26 "In12.Cu" signal "GND5")
		(28 "In13.Cu" signal "IN5")
		(30 "In14.Cu" signal "GND6")
		(32 "In15.Cu" signal "IN6")
		(34 "In16.Cu" signal "GND7")
		(2 "B.Cu" signal "BOTTOM")
		(9 "F.Adhes" user "F.Adhesive")
		(11 "B.Adhes" user "B.Adhesive")
		(13 "F.Paste" user "Package Geometry/Pastemask Top")
		(15 "B.Paste" user "Package Geometry/Pastemask Bottom")
		(5 "F.SilkS" user "Ref Des/Silkscreen Top")
		(7 "B.SilkS" user "Ref Des/Silkscreen Bottom")
		(1 "F.Mask" user "Board Geometry/Soldermask Top")
		(3 "B.Mask" user "Board Geometry/Soldermask Bottom")
		(17 "Dwgs.User" user "User.Drawings")
		(19 "Cmts.User" user "User.Comments")
		(21 "Eco1.User" user "User.Eco1")
		(23 "Eco2.User" user "User.Eco2")
		(25 "Edge.Cuts" user "Board Geometry/Outline")
		(27 "Margin" user)
		(31 "F.CrtYd" user "Package Geometry/Place Bound Top")
		(29 "B.CrtYd" user "Package Geometry/Place Bound Bottom")
		(35 "F.Fab" user "Ref Des/Assembly Top")
		(33 "B.Fab" user "Ref Des/Assembly Bottom")
	)
	(footprint ""
		(layer "B.Cu")
		(at 430.80051 -194.88531 180)
		(property "Reference" "R1576"
			(at 0 0 0)
			(layer "B.SilkS")
			(hide yes)
			(effects
				(font
					(size 1.27 1.27)
				)
				(justify mirror)
			)
		)
		(property "Value" ""
			(at 0 0 0)
			(layer "B.Fab")
			(effects
				(font
					(size 1.27 1.27)
				)
				(justify mirror)
			)
		)
		(duplicate_pad_numbers_are_jumpers no)
		(fp_line
			(start 0.7874 0.4064)
			(end 0.7874 -0.4064)
			(stroke
				(width 0.1524)
				(type default)
			)
			(layer "B.SilkS")
		)
		(fp_line
			(start 0.7874 -0.4064)
			(end -0.7874 -0.4064)
			(stroke
				(width 0.1524)
				(type default)
			)
			(layer "B.SilkS")
		)
		(fp_line
			(start -0.7874 0.4064)
			(end 0.7874 0.4064)
			(stroke
				(width 0.1524)
				(type default)
			)
			(layer "B.SilkS")
		)
		(fp_line
			(start -0.7874 -0.4064)
			(end -0.7874 0.4064)
			(stroke
				(width 0.1524)
				(type default)
			)
			(layer "B.SilkS")
		)
		(fp_line
			(start 0.67945 0.3048)
			(end 0.67945 -0.305054)
			(stroke
				(width 0.1)
				(type default)
			)
			(layer "B.Fab")
		)
		(fp_line
			(start 0.67945 -0.305054)
			(end 0.12065 -0.305054)
			(stroke
				(width 0.1)
				(type default)
			)
			(layer "B.Fab")
		)
		(fp_line
			(start 0.12065 0.3048)
			(end 0.67945 0.3048)
			(stroke
				(width 0.1)
				(type default)
			)
			(layer "B.Fab")
		)
		(fp_line
			(start 0.12065 0.2794)
			(end 0.12065 0.3048)
			(stroke
				(width 0.1)
				(type default)
			)
			(layer "B.Fab")
		)
		(fp_line
			(start 0.12065 -0.2794)
			(end -0.12065 -0.2794)
			(stroke
				(width 0.1)
				(type default)
			)
			(layer "B.Fab")
		)
		(fp_line
			(start 0.12065 -0.305054)
			(end 0.12065 -0.2794)
			(stroke
				(width 0.1)
				(type default)
			)
			(layer "B.Fab")
		)
		(fp_line
			(start -0.120396 0.3048)
			(end -0.120396 0.2794)
			(stroke
				(width 0.1)
				(type default)
			)
			(layer "B.Fab")
		)
		(fp_line
			(start -0.120396 0.2794)
			(end 0.12065 0.2794)
			(stroke
				(width 0.1)
				(type default)
			)
			(layer "B.Fab")
		)
		(fp_line
			(start -0.12065 -0.2794)
			(end -0.12065 -0.3048)
			(stroke
				(width 0.1)
				(type default)
			)
			(layer "B.Fab")
		)
		(fp_line
			(start -0.12065 -0.3048)
			(end -0.67945 -0.3048)
			(stroke
				(width 0.1)
				(type default)
			)
			(layer "B.Fab")
		)
		(fp_line
			(start -0.67945 0.3048)
			(end -0.120396 0.3048)
			(stroke
				(width 0.1)
				(type default)
			)
			(layer "B.Fab")
		)
		(fp_line
			(start -0.67945 -0.3048)
			(end -0.67945 0.3048)
			(stroke
				(width 0.1)
				(type default)
			)
			(layer "B.Fab")
		)
		(pad "1" smd circle
			(at 0.40005 0)
			(size 0 0)
			(layers "B.Cu" "B.Mask" "B.Paste")
			(net "I3C_SPD_DDRGL_CPU0_SCL")
		)
		(pad "2" smd circle
			(at -0.40005 0)
			(size 0 0)
			(layers "B.Cu" "B.Mask" "B.Paste")
			(net "I3C_SPD_DDRI_CPU0_SCL")
		)
	)
	(footprint ""
		(layer "B.Cu")
		(at 188.071506 -126.833376 -90)
		(property "Reference" "R1558"
			(at 0 0 90)
			(layer "B.SilkS")
			(hide yes)
			(effects
				(font
					(size 1.27 1.27)
				)
				(justify mirror)
			)
		)
		(property "Value" ""
			(at 0 0 90)
			(layer "B.Fab")
			(effects
				(font
					(size 1.27 1.27)
				)
				(justify mirror)
			)
		)
		(duplicate_pad_numbers_are_jumpers no)
		(fp_line
			(start -0.7874 0.4064)
			(end 0.7874 0.4064)
			(stroke
				(width 0.1524)
				(type default)
			)
			(layer "B.SilkS")
		)
		(fp_line
			(start 0.7874 0.4064)
			(end 0.7874 -0.4064)
			(stroke
				(width 0.1524)
				(type default)
			)
			(layer "B.SilkS")
		)
		(fp_line
			(start -0.7874 -0.4064)
			(end -0.7874 0.4064)
			(stroke
				(width 0.1524)
				(type default)
			)
			(layer "B.SilkS")
		)
		(fp_line
			(start 0.7874 -0.4064)
			(end -0.7874 -0.4064)
			(stroke
				(width 0.1524)
				(type default)
			)
			(layer "B.SilkS")
		)
		(fp_line
			(start -0.67945 0.3048)
			(end -0.120396 0.3048)
			(stroke
				(width 0.1)
				(type default)
			)
			(layer "B.Fab")
		)
		(fp_line
			(start -0.120396 0.3048)
			(end -0.120396 0.2794)
			(stroke
				(width 0.1)
				(type default)
			)
			(layer "B.Fab")
		)
		(fp_line
			(start 0.12065 0.3048)
			(end 0.67945 0.3048)
			(stroke
				(width 0.1)
				(type default)
			)
			(layer "B.Fab")
		)
		(fp_line
			(start 0.67945 0.3048)
			(end 0.67945 -0.305054)
			(stroke
				(width 0.1)
				(type default)
			)
			(layer "B.Fab")
		)
		(fp_line
			(start -0.120396 0.2794)
			(end 0.12065 0.2794)
			(stroke
				(width 0.1)
				(type default)
			)
			(layer "B.Fab")
		)
		(fp_line
			(start 0.12065 0.2794)
			(end 0.12065 0.3048)
			(stroke
				(width 0.1)
				(type default)
			)
			(layer "B.Fab")
		)
		(fp_line
			(start -0.12065 -0.2794)
			(end -0.12065 -0.3048)
			(stroke
				(width 0.1)
				(type default)
			)
			(layer "B.Fab")
		)
		(fp_line
			(start 0.12065 -0.2794)
			(end -0.12065 -0.2794)
			(stroke
				(width 0.1)
				(type default)
			)
			(layer "B.Fab")
		)
		(fp_line
			(start -0.67945 -0.3048)
			(end -0.67945 0.3048)
			(stroke
				(width 0.1)
				(type default)
			)
			(layer "B.Fab")
		)
		(fp_line
			(start -0.12065 -0.3048)
			(end -0.67945 -0.3048)
			(stroke
				(width 0.1)
				(type default)
			)
			(layer "B.Fab")
		)
		(fp_line
			(start 0.12065 -0.305054)
			(end 0.12065 -0.2794)
			(stroke
				(width 0.1)
				(type default)
			)
			(layer "B.Fab")
		)
		(fp_line
			(start 0.67945 -0.305054)
			(end 0.12065 -0.305054)
			(stroke
				(width 0.1)
				(type default)
			)
			(layer "B.Fab")
		)
		(pad "1" smd circle
			(at 0.40005 0 90)
			(size 0 0)
			(layers "B.Cu" "B.Mask" "B.Paste")
			(net "RST_ESPI_CPU0_RSTOUT_R_N")
		)
		(pad "2" smd circle
			(at -0.40005 0 90)
			(size 0 0)
			(layers "B.Cu" "B.Mask" "B.Paste")
			(net "RST_ESPI_CPU0_RSTOUT_N")
		)
	)
)
